# S9S_MB_2U (Grand Teton) — schematic netlist excerpt (pin names and nets, part order shuffled) for the footprints in the layout excerpt that follows; sources: Cadence DE-HDL packaged netlist, KiCad conversion of 03242023_DA0F0TMBIJ0_F0T_Motherboard_J_brd_V01_OCP.brd

R4081  Q_RES  10K 1% CHIP  pkg 0402LF  page 212 : A = P3V3_AUX ; B = CLK_GEN2_SMB_SADR
R3286  Q_RES  1K 1% EMPTY  pkg 0402LF  page 166 : A = P3V3_AUX ; B = FM_P2E_SWB

(kicad_pcb
	(version 20260206)
	(generator "pcbnew")
	(generator_version "10.0")
	(general
		(thickness 1.6)
		(legacy_teardrops no)
	)
	(paper "A4")
	(title_block
		(title "03242023_DA0F0TMBIJ0_F0T_Motherboard_J_brd_V01_OCP.brd")
		(comment 1 "Grand Teton / footprints 3952-3953 of 6105")
	)
	(layers
		(0 "F.Cu" signal "TOP")
		(4 "In1.Cu" signal "GND")
		(6 "In2.Cu" signal "IN1")
		(8 "In3.Cu" signal "GND1")
		(10 "In4.Cu" signal "IN2")
		(12 "In5.Cu" signal "GND2")
		(14 "In6.Cu" signal "IN3")
		(16 "In7.Cu" signal "GND3")
		(18 "In8.Cu" signal "VCC")
		(20 "In9.Cu" signal "VCC1")
		(22 "In10.Cu" signal "GND4")
		(24 "In11.Cu" signal "IN4")
		(26 "In12.Cu" signal "GND5")
		(28 "In13.Cu" signal "IN5")
		(30 "In14.Cu" signal "GND6")
		(32 "In15.Cu" signal "IN6")
		(34 "In16.Cu" signal "GND7")
		(2 "B.Cu" signal "BOTTOM")
		(9 "F.Adhes" user "F.Adhesive")
		(11 "B.Adhes" user "B.Adhesive")
		(13 "F.Paste" user "Package Geometry/Pastemask Top")
		(15 "B.Paste" user "Package Geometry/Pastemask Bottom")
		(5 "F.SilkS" user "Ref Des/Silkscreen Top")
		(7 "B.SilkS" user "Ref Des/Silkscreen Bottom")
		(1 "F.Mask" user "Board Geometry/Soldermask Top")
		(3 "B.Mask" user "Board Geometry/Soldermask Bottom")
		(17 "Dwgs.User" user "User.Drawings")
		(19 "Cmts.User" user "User.Comments")
		(21 "Eco1.User" user "User.Eco1")
		(23 "Eco2.User" user "User.Eco2")
		(25 "Edge.Cuts" user "Board Geometry/Outline")
		(27 "Margin" user)
		(31 "F.CrtYd" user "Package Geometry/Place Bound Top")
		(29 "B.CrtYd" user "Package Geometry/Place Bound Bottom")
		(35 "F.Fab" user "Ref Des/Assembly Top")
		(33 "B.Fab" user "Ref Des/Assembly Bottom")
	)
	(footprint ""
		(layer "F.Cu")
		(at 27.628596 -389.304276 180)
		(property "Reference" "R3286"
			(at 0 0 180)
			(layer "F.SilkS")
			(hide yes)
			(effects
				(font
					(size 1.27 1.27)
				)
			)
		)
		(property "Value" ""
			(at 0 0 180)
			(layer "F.Fab")
			(effects
				(font
					(size 1.27 1.27)
				)
			)
		)
		(duplicate_pad_numbers_are_jumpers no)
		(fp_line
			(start 0.7874 0.4064)
			(end -0.7874 0.4064)
			(stroke
				(width 0.1524)
				(type default)
			)
			(layer "F.SilkS")
		)
		(fp_line
			(start 0.7874 -0.4064)
			(end 0.7874 0.4064)
			(stroke
				(width 0.1524)
				(type default)
			)
			(layer "F.SilkS")
		)
		(fp_line
			(start -0.7874 0.4064)
			(end -0.7874 -0.4064)
			(stroke
				(width 0.1524)
				(type default)
			)
			(layer "F.SilkS")
		)
		(fp_line
			(start -0.7874 -0.4064)
			(end 0.7874 -0.4064)
			(stroke
				(width 0.1524)
				(type default)
			)
			(layer "F.SilkS")
		)
		(fp_line
			(start 0.67945 0.3048)
			(end 0.120396 0.3048)
			(stroke
				(width 0.1)
				(type default)
			)
			(layer "F.Fab")
		)
		(fp_line
			(start 0.67945 -0.3048)
			(end 0.67945 0.3048)
			(stroke
				(width 0.1)
				(type default)
			)
			(layer "F.Fab")
		)
		(fp_line
			(start 0.12065 -0.2794)
			(end 0.12065 -0.3048)
			(stroke
				(width 0.1)
				(type default)
			)
			(layer "F.Fab")
		)
		(fp_line
			(start 0.12065 -0.3048)
			(end 0.67945 -0.3048)
			(stroke
				(width 0.1)
				(type default)
			)
			(layer "F.Fab")
		)
		(fp_line
			(start 0.120396 0.3048)
			(end 0.120396 0.2794)
			(stroke
				(width 0.1)
				(type default)
			)
			(layer "F.Fab")
		)
		(fp_line
			(start 0.120396 0.2794)
			(end -0.12065 0.2794)
			(stroke
				(width 0.1)
				(type default)
			)
			(layer "F.Fab")
		)
		(fp_line
			(start -0.12065 0.3048)
			(end -0.67945 0.3048)
			(stroke
				(width 0.1)
				(type default)
			)
			(layer "F.Fab")
		)
		(fp_line
			(start -0.12065 0.2794)
			(end -0.12065 0.3048)
			(stroke
				(width 0.1)
				(type default)
			)
			(layer "F.Fab")
		)
		(fp_line
			(start -0.12065 -0.2794)
			(end 0.12065 -0.2794)
			(stroke
				(width 0.1)
				(type default)
			)
			(layer "F.Fab")
		)
		(fp_line
			(start -0.12065 -0.305054)
			(end -0.12065 -0.2794)
			(stroke
				(width 0.1)
				(type default)
			)
			(layer "F.Fab")
		)
		(fp_line
			(start -0.67945 0.3048)
			(end -0.67945 -0.305054)
			(stroke
				(width 0.1)
				(type default)
			)
			(layer "F.Fab")
		)
		(fp_line
			(start -0.67945 -0.305054)
			(end -0.12065 -0.305054)
			(stroke
				(width 0.1)
				(type default)
			)
			(layer "F.Fab")
		)
		(pad "1" smd circle
			(at -0.40005 0 180)
			(size 0 0)
			(layers "F.Cu" "F.Mask" "F.Paste")
			(net "P3V3_AUX")
		)
		(pad "2" smd circle
			(at 0.40005 0 180)
			(size 0 0)
			(layers "F.Cu" "F.Mask" "F.Paste")
			(net "FM_P2E_SWB")
		)
	)
	(footprint ""
		(layer "F.Cu")
		(at 240.61674 -253.345188 180)
		(property "Reference" "R4081"
			(at 0 0 180)
			(layer "F.SilkS")
			(hide yes)
			(effects
				(font
					(size 1.27 1.27)
				)
			)
		)
		(property "Value" ""
			(at 0 0 180)
			(layer "F.Fab")
			(effects
				(font
					(size 1.27 1.27)
				)
			)
		)
		(duplicate_pad_numbers_are_jumpers no)
		(fp_line
			(start 0.7874 0.4064)
			(end -0.7874 0.4064)
			(stroke
				(width 0.1524)
				(type default)
			)
			(layer "F.SilkS")
		)
		(fp_line
			(start 0.7874 -0.4064)
			(end 0.7874 0.4064)
			(stroke
				(width 0.1524)
				(type default)
			)
			(layer "F.SilkS")
		)
		(fp_line
			(start -0.7874 0.4064)
			(end -0.7874 -0.4064)
			(stroke
				(width 0.1524)
				(type default)
			)
			(layer "F.SilkS")
		)
		(fp_line
			(start -0.7874 -0.4064)
			(end 0.7874 -0.4064)
			(stroke
				(width 0.1524)
				(type default)
			)
			(layer "F.SilkS")
		)
		(fp_line
			(start 0.67945 0.3048)
			(end 0.120396 0.3048)
			(stroke
				(width 0.1)
				(type default)
			)
			(layer "F.Fab")
		)
		(fp_line
			(start 0.67945 -0.3048)
			(end 0.67945 0.3048)
			(stroke
				(width 0.1)
				(type default)
			)
			(layer "F.Fab")
		)
		(fp_line
			(start 0.12065 -0.2794)
			(end 0.12065 -0.3048)
			(stroke
				(width 0.1)
				(type default)
			)
			(layer "F.Fab")
		)
		(fp_line
			(start 0.12065 -0.3048)
			(end 0.67945 -0.3048)
			(stroke
				(width 0.1)
				(type default)
			)
			(layer "F.Fab")
		)
		(fp_line
			(start 0.120396 0.3048)
			(end 0.120396 0.2794)
			(stroke
				(width 0.1)
				(type default)
			)
			(layer "F.Fab")
		)
		(fp_line
			(start 0.120396 0.2794)
			(end -0.12065 0.2794)
			(stroke
				(width 0.1)
				(type default)
			)
			(layer "F.Fab")
		)
		(fp_line
			(start -0.12065 0.3048)
			(end -0.67945 0.3048)
			(stroke
				(width 0.1)
				(type default)
			)
			(layer "F.Fab")
		)
		(fp_line
			(start -0.12065 0.2794)
			(end -0.12065 0.3048)
			(stroke
				(width 0.1)
				(type default)
			)
			(layer "F.Fab")
		)
		(fp_line
			(start -0.12065 -0.2794)
			(end 0.12065 -0.2794)
			(stroke
				(width 0.1)
				(type default)
			)
			(layer "F.Fab")
		)
		(fp_line
			(start -0.12065 -0.305054)
			(end -0.12065 -0.2794)
			(stroke
				(width 0.1)
				(type default)
			)
			(layer "F.Fab")
		)
		(fp_line
			(start -0.67945 0.3048)
			(end -0.67945 -0.305054)
			(stroke
				(width 0.1)
				(type default)
			)
			(layer "F.Fab")
		)
		(fp_line
			(start -0.67945 -0.305054)
			(end -0.12065 -0.305054)
			(stroke
				(width 0.1)
				(type default)
			)
			(layer "F.Fab")
		)
		(pad "1" smd circle
			(at -0.40005 0 180)
			(size 0 0)
			(layers "F.Cu" "F.Mask" "F.Paste")
			(net "P3V3_AUX")
		)
		(pad "2" smd circle
			(at 0.40005 0 180)
			(size 0 0)
			(layers "F.Cu" "F.Mask" "F.Paste")
			(net "CLK_GEN2_SMB_SADR")
		)
	)
)
